# S9S_MB_2U (Grand Teton) — schematic netlist excerpt (pin names and nets, part order shuffled) for the footprints in the layout excerpt that follows; sources: Cadence DE-HDL packaged netlist, KiCad conversion of 03242023_DA0F0TMBIJ0_F0T_Motherboard_J_brd_V01_OCP.brd

R496  Q_RES  113 1% CHIP  pkg 0402LF  page 180 : A = PD_PCH_USB2_COMP ; B = GND
R3075  Q_RES  130 1% CHIP  pkg 0402LF  page 252 : A = LED_PWRGD_PS_PWROK_PLD ; B = P3V3_AUX

(kicad_pcb
	(version 20260206)
	(generator "pcbnew")
	(generator_version "10.0")
	(general
		(thickness 1.6)
		(legacy_teardrops no)
	)
	(paper "A4")
	(title_block
		(title "03242023_DA0F0TMBIJ0_F0T_Motherboard_J_brd_V01_OCP.brd")
		(comment 1 "Grand Teton / footprints 2280-2281 of 6105")
	)
	(layers
		(0 "F.Cu" signal "TOP")
		(4 "In1.Cu" signal "GND")
		(6 "In2.Cu" signal "IN1")
		(8 "In3.Cu" signal "GND1")
		(10 "In4.Cu" signal "IN2")
		(12 "In5.Cu" signal "GND2")
		(14 "In6.Cu" signal "IN3")
		(16 "In7.Cu" signal "GND3")
		(18 "In8.Cu" signal "VCC")
		(20 "In9.Cu" signal "VCC1")
		(22 "In10.Cu" signal "GND4")
		(24 "In11.Cu" signal "IN4")
		(26 "In12.Cu" signal "GND5")
		(28 "In13.Cu" signal "IN5")
		(30 "In14.Cu" signal "GND6")
		(32 "In15.Cu" signal "IN6")
		(34 "In16.Cu" signal "GND7")
		(2 "B.Cu" signal "BOTTOM")
		(9 "F.Adhes" user "F.Adhesive")
		(11 "B.Adhes" user "B.Adhesive")
		(13 "F.Paste" user "Package Geometry/Pastemask Top")
		(15 "B.Paste" user "Package Geometry/Pastemask Bottom")
		(5 "F.SilkS" user "Ref Des/Silkscreen Top")
		(7 "B.SilkS" user "Ref Des/Silkscreen Bottom")
		(1 "F.Mask" user "Board Geometry/Soldermask Top")
		(3 "B.Mask" user "Board Geometry/Soldermask Bottom")
		(17 "Dwgs.User" user "User.Drawings")
		(19 "Cmts.User" user "User.Comments")
		(21 "Eco1.User" user "User.Eco1")
		(23 "Eco2.User" user "User.Eco2")
		(25 "Edge.Cuts" user "Board Geometry/Outline")
		(27 "Margin" user)
		(31 "F.CrtYd" user "Package Geometry/Place Bound Top")
		(29 "B.CrtYd" user "Package Geometry/Place Bound Bottom")
		(35 "F.Fab" user "Ref Des/Assembly Top")
		(33 "B.Fab" user "Ref Des/Assembly Bottom")
	)
	(footprint ""
		(layer "F.Cu")
		(at 350.1517 -30.520894 -90)
		(property "Reference" "R496"
			(at 0 0 270)
			(layer "F.SilkS")
			(hide yes)
			(effects
				(font
					(size 1.27 1.27)
				)
			)
		)
		(property "Value" ""
			(at 0 0 270)
			(layer "F.Fab")
			(effects
				(font
					(size 1.27 1.27)
				)
			)
		)
		(duplicate_pad_numbers_are_jumpers no)
		(fp_line
			(start -0.7874 0.4064)
			(end -0.7874 -0.4064)
			(stroke
				(width 0.1524)
				(type default)
			)
			(layer "F.SilkS")
		)
		(fp_line
			(start 0.7874 0.4064)
			(end -0.7874 0.4064)
			(stroke
				(width 0.1524)
				(type default)
			)
			(layer "F.SilkS")
		)
		(fp_line
			(start -0.7874 -0.4064)
			(end 0.7874 -0.4064)
			(stroke
				(width 0.1524)
				(type default)
			)
			(layer "F.SilkS")
		)
		(fp_line
			(start 0.7874 -0.4064)
			(end 0.7874 0.4064)
			(stroke
				(width 0.1524)
				(type default)
			)
			(layer "F.SilkS")
		)
		(fp_line
			(start -0.67945 0.3048)
			(end -0.67945 -0.305054)
			(stroke
				(width 0.1)
				(type default)
			)
			(layer "F.Fab")
		)
		(fp_line
			(start -0.12065 0.3048)
			(end -0.67945 0.3048)
			(stroke
				(width 0.1)
				(type default)
			)
			(layer "F.Fab")
		)
		(fp_line
			(start 0.120396 0.3048)
			(end 0.120396 0.2794)
			(stroke
				(width 0.1)
				(type default)
			)
			(layer "F.Fab")
		)
		(fp_line
			(start 0.67945 0.3048)
			(end 0.120396 0.3048)
			(stroke
				(width 0.1)
				(type default)
			)
			(layer "F.Fab")
		)
		(fp_line
			(start -0.12065 0.2794)
			(end -0.12065 0.3048)
			(stroke
				(width 0.1)
				(type default)
			)
			(layer "F.Fab")
		)
		(fp_line
			(start 0.120396 0.2794)
			(end -0.12065 0.2794)
			(stroke
				(width 0.1)
				(type default)
			)
			(layer "F.Fab")
		)
		(fp_line
			(start -0.12065 -0.2794)
			(end 0.12065 -0.2794)
			(stroke
				(width 0.1)
				(type default)
			)
			(layer "F.Fab")
		)
		(fp_line
			(start 0.12065 -0.2794)
			(end 0.12065 -0.3048)
			(stroke
				(width 0.1)
				(type default)
			)
			(layer "F.Fab")
		)
		(fp_line
			(start 0.12065 -0.3048)
			(end 0.67945 -0.3048)
			(stroke
				(width 0.1)
				(type default)
			)
			(layer "F.Fab")
		)
		(fp_line
			(start 0.67945 -0.3048)
			(end 0.67945 0.3048)
			(stroke
				(width 0.1)
				(type default)
			)
			(layer "F.Fab")
		)
		(fp_line
			(start -0.67945 -0.305054)
			(end -0.12065 -0.305054)
			(stroke
				(width 0.1)
				(type default)
			)
			(layer "F.Fab")
		)
		(fp_line
			(start -0.12065 -0.305054)
			(end -0.12065 -0.2794)
			(stroke
				(width 0.1)
				(type default)
			)
			(layer "F.Fab")
		)
		(pad "1" smd circle
			(at -0.40005 0 270)
			(size 0 0)
			(layers "F.Cu" "F.Mask" "F.Paste")
			(net "PD_PCH_USB2_COMP")
		)
		(pad "2" smd circle
			(at 0.40005 0 270)
			(size 0 0)
			(layers "F.Cu" "F.Mask" "F.Paste")
			(net "GND")
		)
	)
	(footprint ""
		(layer "F.Cu")
		(at 93.090492 -74.736706 -90)
		(property "Reference" "R3075"
			(at 0 0 270)
			(layer "F.SilkS")
			(hide yes)
			(effects
				(font
					(size 1.27 1.27)
				)
			)
		)
		(property "Value" ""
			(at 0 0 270)
			(layer "F.Fab")
			(effects
				(font
					(size 1.27 1.27)
				)
			)
		)
		(duplicate_pad_numbers_are_jumpers no)
		(fp_line
			(start -0.7874 0.4064)
			(end -0.7874 -0.4064)
			(stroke
				(width 0.1524)
				(type default)
			)
			(layer "F.SilkS")
		)
		(fp_line
			(start 0.7874 0.4064)
			(end -0.7874 0.4064)
			(stroke
				(width 0.1524)
				(type default)
			)
			(layer "F.SilkS")
		)
		(fp_line
			(start -0.7874 -0.4064)
			(end 0.7874 -0.4064)
			(stroke
				(width 0.1524)
				(type default)
			)
			(layer "F.SilkS")
		)
		(fp_line
			(start 0.7874 -0.4064)
			(end 0.7874 0.4064)
			(stroke
				(width 0.1524)
				(type default)
			)
			(layer "F.SilkS")
		)
		(fp_line
			(start -0.67945 0.3048)
			(end -0.67945 -0.305054)
			(stroke
				(width 0.1)
				(type default)
			)
			(layer "F.Fab")
		)
		(fp_line
			(start -0.12065 0.3048)
			(end -0.67945 0.3048)
			(stroke
				(width 0.1)
				(type default)
			)
			(layer "F.Fab")
		)
		(fp_line
			(start 0.120396 0.3048)
			(end 0.120396 0.2794)
			(stroke
				(width 0.1)
				(type default)
			)
			(layer "F.Fab")
		)
		(fp_line
			(start 0.67945 0.3048)
			(end 0.120396 0.3048)
			(stroke
				(width 0.1)
				(type default)
			)
			(layer "F.Fab")
		)
		(fp_line
			(start -0.12065 0.2794)
			(end -0.12065 0.3048)
			(stroke
				(width 0.1)
				(type default)
			)
			(layer "F.Fab")
		)
		(fp_line
			(start 0.120396 0.2794)
			(end -0.12065 0.2794)
			(stroke
				(width 0.1)
				(type default)
			)
			(layer "F.Fab")
		)
		(fp_line
			(start -0.12065 -0.2794)
			(end 0.12065 -0.2794)
			(stroke
				(width 0.1)
				(type default)
			)
			(layer "F.Fab")
		)
		(fp_line
			(start 0.12065 -0.2794)
			(end 0.12065 -0.3048)
			(stroke
				(width 0.1)
				(type default)
			)
			(layer "F.Fab")
		)
		(fp_line
			(start 0.12065 -0.3048)
			(end 0.67945 -0.3048)
			(stroke
				(width 0.1)
				(type default)
			)
			(layer "F.Fab")
		)
		(fp_line
			(start 0.67945 -0.3048)
			(end 0.67945 0.3048)
			(stroke
				(width 0.1)
				(type default)
			)
			(layer "F.Fab")
		)
		(fp_line
			(start -0.67945 -0.305054)
			(end -0.12065 -0.305054)
			(stroke
				(width 0.1)
				(type default)
			)
			(layer "F.Fab")
		)
		(fp_line
			(start -0.12065 -0.305054)
			(end -0.12065 -0.2794)
			(stroke
				(width 0.1)
				(type default)
			)
			(layer "F.Fab")
		)
		(pad "1" smd circle
			(at -0.40005 0 270)
			(size 0 0)
			(layers "F.Cu" "F.Mask" "F.Paste")
			(net "LED_PWRGD_PS_PWROK_PLD")
		)
		(pad "2" smd circle
			(at 0.40005 0 270)
			(size 0 0)
			(layers "F.Cu" "F.Mask" "F.Paste")
			(net "P3V3_AUX")
		)
	)
)
